# TIMECARD (Time Appliance Project (Time Card)) — schematic netlist excerpt (pin names and nets, part order shuffled) for the footprints in the layout excerpt that follows; sources: Cadence DE-HDL packaged netlist, KiCad conversion of R4006-B0001-02_R01.brd

R465  RESISTOR  0OHM -  pkg SMC_0402R_H016  page 24 : \1\ = FPGA_FLASH_DQ3 ; \2\ = FLASH_DQ3
R277  RESISTOR  100OHM 1%  pkg SMC_0402R_H016  page 13 : \1\ = FPGA_OUT_MAC_PPS_IN1P ; \2\ = FPGA_OUT_MAC_PPS_IN1N

(kicad_pcb
	(version 20260206)
	(generator "pcbnew")
	(generator_version "10.0")
	(general
		(thickness 1.6)
		(legacy_teardrops no)
	)
	(paper "A4")
	(title_block
		(title "timecard-production-celestica-r4006 — R4006-B0001-02_R01.brd")
		(comment 1 "Time Appliance Project (Time Card) / footprints 227-228 of 1113")
	)
	(layers
		(0 "F.Cu" signal "TOP")
		(4 "In1.Cu" signal "L02_GND1")
		(6 "In2.Cu" signal "L03_SIG1")
		(8 "In3.Cu" signal "L04_GND2")
		(10 "In4.Cu" signal "L05_VCC1")
		(12 "In5.Cu" signal "L06_VCC2")
		(14 "In6.Cu" signal "L07_GND3")
		(16 "In7.Cu" signal "L08_SIG2")
		(18 "In8.Cu" signal "L09_GND4")
		(2 "B.Cu" signal "BOTTOM")
		(9 "F.Adhes" user "F.Adhesive")
		(11 "B.Adhes" user "B.Adhesive")
		(13 "F.Paste" user "Package Geometry/Pastemask Top")
		(15 "B.Paste" user "Package Geometry/Pastemask Bottom")
		(5 "F.SilkS" user "Ref Des/Silkscreen Top")
		(7 "B.SilkS" user "Ref Des/Silkscreen Bottom")
		(1 "F.Mask" user "Board Geometry/Soldermask Top")
		(3 "B.Mask" user "Board Geometry/Soldermask Bottom")
		(17 "Dwgs.User" user "User.Drawings")
		(19 "Cmts.User" user "User.Comments")
		(21 "Eco1.User" user "User.Eco1")
		(23 "Eco2.User" user "User.Eco2")
		(25 "Edge.Cuts" user "Board Geometry/Outline")
		(27 "Margin" user)
		(31 "F.CrtYd" user "Package Geometry/Place Bound Top")
		(29 "B.CrtYd" user "Package Geometry/Place Bound Bottom")
		(35 "F.Fab" user "Ref Des/Assembly Top")
		(33 "B.Fab" user "Ref Des/Assembly Bottom")
	)
	(footprint ""
		(layer "F.Cu")
		(at 82.7786 -52.959 -90)
		(property "Reference" "R277"
			(at 13.589 0.96393 90)
			(unlocked yes)
			(layer "F.SilkS")
			(effects
				(font
					(size 0.7874 0.5842)
					(thickness 0.1524)
				)
			)
		)
		(property "Value" "VAL*"
			(at 0.02032 2.13233 270)
			(unlocked yes)
			(layer "F.Fab")
			(hide yes)
			(effects
				(font
					(size 0.7874 0.5842)
					(thickness 0.1524)
				)
			)
		)
		(property "Tolerance" "TOL*"
			(at 0.044704 3.05435 270)
			(unlocked yes)
			(layer "Cmts.User")
			(hide yes)
			(effects
				(font
					(size 0.7874 0.5842)
					(thickness 0.1524)
				)
			)
		)
		(property "User Part Number" "PARTNUM*"
			(at 0.02032 4.024884 270)
			(unlocked yes)
			(layer "Cmts.User")
			(hide yes)
			(effects
				(font
					(size 0.7874 0.5842)
					(thickness 0.1524)
				)
			)
		)
		(property "Device Type" "RESISTOR-G155-11000-01,100OHM,A"
			(at 0.008382 1.210564 270)
			(unlocked yes)
			(layer "F.Fab")
			(hide yes)
			(effects
				(font
					(size 0.7874 0.5842)
					(thickness 0.1524)
				)
			)
		)
		(duplicate_pad_numbers_are_jumpers no)
		(fp_line
			(start -1.143 0.5588)
			(end 1.143 0.5588)
			(stroke
				(width 0.1)
				(type default)
			)
			(layer "F.SilkS")
		)
		(fp_line
			(start 1.143 0.5588)
			(end 1.143 -0.5588)
			(stroke
				(width 0.1)
				(type default)
			)
			(layer "F.SilkS")
		)
		(fp_line
			(start -1.143 -0.5588)
			(end -1.143 0.5588)
			(stroke
				(width 0.1)
				(type default)
			)
			(layer "F.SilkS")
		)
		(fp_line
			(start 1.143 -0.5588)
			(end -1.143 -0.5588)
			(stroke
				(width 0.1)
				(type default)
			)
			(layer "F.SilkS")
		)
		(fp_rect
			(start 1.143 0.5588)
			(end -1.143 -0.5588)
			(stroke
				(width 0)
				(type default)
			)
			(fill no)
			(layer "F.CrtYd")
		)
		(fp_line
			(start -0.508 0.3048)
			(end 0.508 0.3048)
			(stroke
				(width 0.1)
				(type default)
			)
			(layer "F.Fab")
		)
		(fp_line
			(start 0.508 0.3048)
			(end 0.508 -0.3048)
			(stroke
				(width 0.1)
				(type default)
			)
			(layer "F.Fab")
		)
		(fp_line
			(start -0.508 -0.3048)
			(end -0.508 0.3048)
			(stroke
				(width 0.1)
				(type default)
			)
			(layer "F.Fab")
		)
		(fp_line
			(start 0.508 -0.3048)
			(end -0.508 -0.3048)
			(stroke
				(width 0.1)
				(type default)
			)
			(layer "F.Fab")
		)
		(pad "1" smd rect
			(at -0.5334 0 270)
			(size 0.7112 0.6096)
			(layers "F.Cu" "F.Mask" "F.Paste")
			(net "FPGA_OUT_MAC_PPS_IN1P")
		)
		(pad "2" smd rect
			(at 0.5334 0 270)
			(size 0.7112 0.6096)
			(layers "F.Cu" "F.Mask" "F.Paste")
			(net "FPGA_OUT_MAC_PPS_IN1N")
		)
		(zone
			(layer "F.Cu")
			(hatch none 0.5)
			(connect_pads
				(clearance 0)
			)
			(min_thickness 0.25)
			(keepout
				(tracks allowed)
				(vias not_allowed)
				(pads allowed)
				(copperpour not_allowed)
				(footprints allowed)
			)
			(placement
				(enabled no)
				(sheetname "")
			)
			(fill
				(thermal_gap 0.5)
				(thermal_bridge_width 0.5)
				(island_removal_mode 0)
			)
			(polygon
				(pts
					(xy 82.4738 -52.8828) (xy 83.0834 -52.8828) (xy 83.0834 -53.0352) (xy 82.4738 -53.0352)
				)
			)
		)
	)
	(footprint ""
		(layer "F.Cu")
		(at 103.632 -87.63 90)
		(property "Reference" "R465"
			(at -1.397 4.61137 90)
			(unlocked yes)
			(layer "F.SilkS")
			(effects
				(font
					(size 0.7874 0.5842)
					(thickness 0.1524)
				)
			)
		)
		(property "Value" "VAL*"
			(at 0.02032 2.13233 90)
			(unlocked yes)
			(layer "F.Fab")
			(hide yes)
			(effects
				(font
					(size 0.7874 0.5842)
					(thickness 0.1524)
				)
			)
		)
		(property "Tolerance" "TOL*"
			(at 0.044704 3.05435 90)
			(unlocked yes)
			(layer "Cmts.User")
			(hide yes)
			(effects
				(font
					(size 0.7874 0.5842)
					(thickness 0.1524)
				)
			)
		)
		(property "User Part Number" "PARTNUM*"
			(at 0.02032 4.024884 90)
			(unlocked yes)
			(layer "Cmts.User")
			(hide yes)
			(effects
				(font
					(size 0.7874 0.5842)
					(thickness 0.1524)
				)
			)
		)
		(property "Device Type" "RESISTOR-G155-100R0-J0,0OHM,-"
			(at 0.008382 1.210564 90)
			(unlocked yes)
			(layer "F.Fab")
			(hide yes)
			(effects
				(font
					(size 0.7874 0.5842)
					(thickness 0.1524)
				)
			)
		)
		(duplicate_pad_numbers_are_jumpers no)
		(fp_line
			(start 1.143 -0.5588)
			(end -1.143 -0.5588)
			(stroke
				(width 0.1)
				(type default)
			)
			(layer "F.SilkS")
		)
		(fp_line
			(start -1.143 -0.5588)
			(end -1.143 0.5588)
			(stroke
				(width 0.1)
				(type default)
			)
			(layer "F.SilkS")
		)
		(fp_line
			(start 1.143 0.5588)
			(end 1.143 -0.5588)
			(stroke
				(width 0.1)
				(type default)
			)
			(layer "F.SilkS")
		)
		(fp_line
			(start -1.143 0.5588)
			(end 1.143 0.5588)
			(stroke
				(width 0.1)
				(type default)
			)
			(layer "F.SilkS")
		)
		(fp_poly
			(pts
				(xy -1.143 0.5588) (xy 1.143 0.5588) (xy 1.143 -0.5588) (xy -1.143 -0.5588)
			)
			(stroke
				(width 0)
				(type default)
			)
			(fill no)
			(layer "F.CrtYd")
		)
		(fp_line
			(start 0.508 -0.3048)
			(end -0.508 -0.3048)
			(stroke
				(width 0.1)
				(type default)
			)
			(layer "F.Fab")
		)
		(fp_line
			(start -0.508 -0.3048)
			(end -0.508 0.3048)
			(stroke
				(width 0.1)
				(type default)
			)
			(layer "F.Fab")
		)
		(fp_line
			(start 0.508 0.3048)
			(end 0.508 -0.3048)
			(stroke
				(width 0.1)
				(type default)
			)
			(layer "F.Fab")
		)
		(fp_line
			(start -0.508 0.3048)
			(end 0.508 0.3048)
			(stroke
				(width 0.1)
				(type default)
			)
			(layer "F.Fab")
		)
		(pad "1" smd rect
			(at -0.5334 0 90)
			(size 0.7112 0.6096)
			(layers "F.Cu" "F.Mask" "F.Paste")
			(net "FPGA_FLASH_DQ3")
		)
		(pad "2" smd rect
			(at 0.5334 0 90)
			(size 0.7112 0.6096)
			(layers "F.Cu" "F.Mask" "F.Paste")
			(net "FLASH_DQ3")
		)
		(zone
			(layer "F.Cu")
			(hatch none 0.5)
			(connect_pads
				(clearance 0)
			)
			(min_thickness 0.25)
			(keepout
				(tracks not_allowed)
				(vias allowed)
				(pads allowed)
				(copperpour not_allowed)
				(footprints allowed)
			)
			(placement
				(enabled no)
				(sheetname "")
			)
			(fill
				(thermal_gap 0.5)
				(thermal_bridge_width 0.5)
				(island_removal_mode 0)
			)
			(polygon
				(pts
					(xy 103.9368 -87.5538) (xy 103.9368 -87.7062) (xy 103.3272 -87.7062) (xy 103.3272 -87.5538)
				)
			)
		)
		(zone
			(layer "F.Cu")
			(hatch none 0.5)
			(connect_pads
				(clearance 0)
			)
			(min_thickness 0.25)
			(keepout
				(tracks allowed)
				(vias not_allowed)
				(pads allowed)
				(copperpour not_allowed)
				(footprints allowed)
			)
			(placement
				(enabled no)
				(sheetname "")
			)
			(fill
				(thermal_gap 0.5)
				(thermal_bridge_width 0.5)
				(island_removal_mode 0)
			)
			(polygon
				(pts
					(xy 103.9368 -87.5538) (xy 103.9368 -87.7062) (xy 103.3272 -87.7062) (xy 103.3272 -87.5538)
				)
			)
		)
	)
)
